(kicad_pcb
	(version 20260206)
	(generator "pcbnew")
	(generator_version "10.0")
	(general
		(thickness 1.6)
		(legacy_teardrops no)
	)
	(paper "A4")
	(title_block
		(title "04192023_DAF0TMB3IC0_F0TG_MB_C_brd_V02_OCP.brd")
		(comment 1 "Grand Teton / footprints 255-260 of 8354")
	)
	(layers
		(0 "F.Cu" signal "TOP")
		(4 "In1.Cu" signal "GND")
		(6 "In2.Cu" signal "IN1")
		(8 "In3.Cu" signal "GND1")
		(10 "In4.Cu" signal "IN2")
		(12 "In5.Cu" signal "GND2")
		(14 "In6.Cu" signal "IN3")
		(16 "In7.Cu" signal "GND3")
		(18 "In8.Cu" signal "VCC")
		(20 "In9.Cu" signal "VCC1")
		(22 "In10.Cu" signal "GND4")
		(24 "In11.Cu" signal "IN4")
		(26 "In12.Cu" signal "GND5")
		(28 "In13.Cu" signal "IN5")
		(30 "In14.Cu" signal "GND6")
		(32 "In15.Cu" signal "IN6")
		(34 "In16.Cu" signal "GND7")
		(2 "B.Cu" signal "BOTTOM")
		(9 "F.Adhes" user "F.Adhesive")
		(11 "B.Adhes" user "B.Adhesive")
		(13 "F.Paste" user "Package Geometry/Pastemask Top")
		(15 "B.Paste" user "Package Geometry/Pastemask Bottom")
		(5 "F.SilkS" user "Ref Des/Silkscreen Top")
		(7 "B.SilkS" user "Ref Des/Silkscreen Bottom")
		(1 "F.Mask" user "Board Geometry/Soldermask Top")
		(3 "B.Mask" user "Board Geometry/Soldermask Bottom")
		(17 "Dwgs.User" user "User.Drawings")
		(19 "Cmts.User" user "User.Comments")
		(21 "Eco1.User" user "User.Eco1")
		(23 "Eco2.User" user "User.Eco2")
		(25 "Edge.Cuts" user "Board Geometry/Outline")
		(27 "Margin" user)
		(31 "F.CrtYd" user "Package Geometry/Place Bound Top")
		(29 "B.CrtYd" user "Package Geometry/Place Bound Bottom")
		(35 "F.Fab" user "Ref Des/Assembly Top")
		(33 "B.Fab" user "Ref Des/Assembly Bottom")
	)
	(footprint ""
		(layer "F.Cu")
		(at 335.28508 -15.996666 -90)
		(property "Reference" "R1444"
			(at 0 0 270)
			(layer "F.SilkS")
			(hide yes)
			(effects
				(font
					(size 1.27 1.27)
				)
			)
		)
		(property "Value" ""
			(at 0 0 270)
			(layer "F.Fab")
			(effects
				(font
					(size 1.27 1.27)
				)
			)
		)
		(duplicate_pad_numbers_are_jumpers no)
		(fp_line
			(start -0.7874 0.4064)
			(end -0.7874 -0.4064)
			(stroke
				(width 0.1524)
				(type default)
			)
			(layer "F.SilkS")
		)
		(fp_line
			(start 0.7874 0.4064)
			(end -0.7874 0.4064)
			(stroke
				(width 0.1524)
				(type default)
			)
			(layer "F.SilkS")
		)
		(fp_line
			(start -0.7874 -0.4064)
			(end 0.7874 -0.4064)
			(stroke
				(width 0.1524)
				(type default)
			)
			(layer "F.SilkS")
		)
		(fp_line
			(start 0.7874 -0.4064)
			(end 0.7874 0.4064)
			(stroke
				(width 0.1524)
				(type default)
			)
			(layer "F.SilkS")
		)
		(fp_line
			(start -0.67945 0.3048)
			(end -0.67945 -0.305054)
			(stroke
				(width 0.1)
				(type default)
			)
			(layer "F.Fab")
		)
		(fp_line
			(start -0.12065 0.3048)
			(end -0.67945 0.3048)
			(stroke
				(width 0.1)
				(type default)
			)
			(layer "F.Fab")
		)
		(fp_line
			(start 0.120396 0.3048)
			(end 0.120396 0.2794)
			(stroke
				(width 0.1)
				(type default)
			)
			(layer "F.Fab")
		)
		(fp_line
			(start 0.67945 0.3048)
			(end 0.120396 0.3048)
			(stroke
				(width 0.1)
				(type default)
			)
			(layer "F.Fab")
		)
		(fp_line
			(start -0.12065 0.2794)
			(end -0.12065 0.3048)
			(stroke
				(width 0.1)
				(type default)
			)
			(layer "F.Fab")
		)
		(fp_line
			(start 0.120396 0.2794)
			(end -0.12065 0.2794)
			(stroke
				(width 0.1)
				(type default)
			)
			(layer "F.Fab")
		)
		(fp_line
			(start -0.12065 -0.2794)
			(end 0.12065 -0.2794)
			(stroke
				(width 0.1)
				(type default)
			)
			(layer "F.Fab")
		)
		(fp_line
			(start 0.12065 -0.2794)
			(end 0.12065 -0.3048)
			(stroke
				(width 0.1)
				(type default)
			)
			(layer "F.Fab")
		)
		(fp_line
			(start 0.12065 -0.3048)
			(end 0.67945 -0.3048)
			(stroke
				(width 0.1)
				(type default)
			)
			(layer "F.Fab")
		)
		(fp_line
			(start 0.67945 -0.3048)
			(end 0.67945 0.3048)
			(stroke
				(width 0.1)
				(type default)
			)
			(layer "F.Fab")
		)
		(fp_line
			(start -0.67945 -0.305054)
			(end -0.12065 -0.305054)
			(stroke
				(width 0.1)
				(type default)
			)
			(layer "F.Fab")
		)
		(fp_line
			(start -0.12065 -0.305054)
			(end -0.12065 -0.2794)
			(stroke
				(width 0.1)
				(type default)
			)
			(layer "F.Fab")
		)
		(pad "1" smd circle
			(at -0.40005 0 270)
			(size 0 0)
			(layers "F.Cu" "F.Mask" "F.Paste")
			(net "P3V3_AUX")
		)
		(pad "2" smd circle
			(at 0.40005 0 270)
			(size 0 0)
			(layers "F.Cu" "F.Mask" "F.Paste")
			(net "LED_BIOS_DBG_MODE_R")
		)
	)
	(footprint ""
		(layer "F.Cu")
		(at 76.971906 -152.990804 90)
		(property "Reference" "PC60"
			(at 0 0 90)
			(layer "F.SilkS")
			(hide yes)
			(effects
				(font
					(size 1.27 1.27)
				)
			)
		)
		(property "Value" ""
			(at 0 0 90)
			(layer "F.Fab")
			(effects
				(font
					(size 1.27 1.27)
				)
			)
		)
		(duplicate_pad_numbers_are_jumpers no)
		(fp_line
			(start 1.524 -0.762)
			(end 1.524 0.762)
			(stroke
				(width 0.1524)
				(type default)
			)
			(layer "F.SilkS")
		)
		(fp_line
			(start -1.524 -0.762)
			(end 1.524 -0.762)
			(stroke
				(width 0.1524)
				(type default)
			)
			(layer "F.SilkS")
		)
		(fp_line
			(start 1.524 0.762)
			(end -1.524 0.762)
			(stroke
				(width 0.1524)
				(type default)
			)
			(layer "F.SilkS")
		)
		(fp_line
			(start -1.524 0.762)
			(end -1.524 -0.762)
			(stroke
				(width 0.1524)
				(type default)
			)
			(layer "F.SilkS")
		)
		(fp_line
			(start 1.1049 -0.724916)
			(end -1.1049 -0.724916)
			(stroke
				(width 0.1)
				(type default)
			)
			(layer "F.Fab")
		)
		(fp_line
			(start -1.1049 -0.724916)
			(end -1.1049 0.724916)
			(stroke
				(width 0.1)
				(type default)
			)
			(layer "F.Fab")
		)
		(fp_line
			(start 1.1049 0.724916)
			(end 1.1049 -0.724916)
			(stroke
				(width 0.1)
				(type default)
			)
			(layer "F.Fab")
		)
		(fp_line
			(start -1.1049 0.724916)
			(end 1.1049 0.724916)
			(stroke
				(width 0.1)
				(type default)
			)
			(layer "F.Fab")
		)
		(pad "1" smd rect
			(at -0.889 0 270)
			(size 1.016 1.27)
			(layers "F.Cu" "F.Mask" "F.Paste")
			(net "SW_P12V_AUX_PVDD18_S5_P1_FLT")
		)
		(pad "2" smd rect
			(at 0.889 0 270)
			(size 1.016 1.27)
			(layers "F.Cu" "F.Mask" "F.Paste")
			(net "GND")
		)
	)
	(footprint ""
		(layer "F.Cu")
		(at 461.689196 -49.453546 -90)
		(property "Reference" "PC591"
			(at 0 0 270)
			(layer "F.SilkS")
			(hide yes)
			(effects
				(font
					(size 1.27 1.27)
				)
			)
		)
		(property "Value" ""
			(at 0 0 270)
			(layer "F.Fab")
			(effects
				(font
					(size 1.27 1.27)
				)
			)
		)
		(duplicate_pad_numbers_are_jumpers no)
		(fp_line
			(start -1.2954 0.5842)
			(end -1.2954 -0.5842)
			(stroke
				(width 0.1524)
				(type default)
			)
			(layer "F.SilkS")
		)
		(fp_line
			(start 1.2954 0.5842)
			(end -1.2954 0.5842)
			(stroke
				(width 0.1524)
				(type default)
			)
			(layer "F.SilkS")
		)
		(fp_line
			(start -1.2954 -0.5842)
			(end 1.2954 -0.5842)
			(stroke
				(width 0.1524)
				(type default)
			)
			(layer "F.SilkS")
		)
		(fp_line
			(start 1.2954 -0.5842)
			(end 1.2954 0.5842)
			(stroke
				(width 0.1524)
				(type default)
			)
			(layer "F.SilkS")
		)
		(fp_line
			(start -0.8636 0.4572)
			(end -0.8636 0.4064)
			(stroke
				(width 0.1)
				(type default)
			)
			(layer "F.Fab")
		)
		(fp_line
			(start 0.8636 0.4572)
			(end -0.8636 0.4572)
			(stroke
				(width 0.1)
				(type default)
			)
			(layer "F.Fab")
		)
		(fp_line
			(start -1.1938 0.4064)
			(end -1.1938 -0.4064)
			(stroke
				(width 0.1)
				(type default)
			)
			(layer "F.Fab")
		)
		(fp_line
			(start -0.8636 0.4064)
			(end -1.1938 0.4064)
			(stroke
				(width 0.1)
				(type default)
			)
			(layer "F.Fab")
		)
		(fp_line
			(start 0.8636 0.4064)
			(end 0.8636 0.4572)
			(stroke
				(width 0.1)
				(type default)
			)
			(layer "F.Fab")
		)
		(fp_line
			(start 1.1938 0.4064)
			(end 0.8636 0.4064)
			(stroke
				(width 0.1)
				(type default)
			)
			(layer "F.Fab")
		)
		(fp_line
			(start -1.1938 -0.4064)
			(end -0.8636 -0.4064)
			(stroke
				(width 0.1)
				(type default)
			)
			(layer "F.Fab")
		)
		(fp_line
			(start -0.8636 -0.4064)
			(end -0.8636 -0.4572)
			(stroke
				(width 0.1)
				(type default)
			)
			(layer "F.Fab")
		)
		(fp_line
			(start 0.8636 -0.4064)
			(end 1.1938 -0.4064)
			(stroke
				(width 0.1)
				(type default)
			)
			(layer "F.Fab")
		)
		(fp_line
			(start 1.1938 -0.4064)
			(end 1.1938 0.4064)
			(stroke
				(width 0.1)
				(type default)
			)
			(layer "F.Fab")
		)
		(fp_line
			(start -0.8636 -0.4572)
			(end 0.8636 -0.4572)
			(stroke
				(width 0.1)
				(type default)
			)
			(layer "F.Fab")
		)
		(fp_line
			(start 0.8636 -0.4572)
			(end 0.8636 -0.4064)
			(stroke
				(width 0.1)
				(type default)
			)
			(layer "F.Fab")
		)
		(pad "1" smd rect
			(at -0.7366 0 180)
			(size 0.7112 0.8128)
			(layers "F.Cu" "F.Mask" "F.Paste")
			(net "P3V3_AUX_VCC")
		)
		(pad "2" smd rect
			(at 0.7366 0 180)
			(size 0.7112 0.8128)
			(layers "F.Cu" "F.Mask" "F.Paste")
			(net "GND")
		)
	)
	(footprint ""
		(layer "F.Cu")
		(at 38.416738 -169.763694 180)
		(property "Reference" "C1338"
			(at 0 0 180)
			(layer "F.SilkS")
			(hide yes)
			(effects
				(font
					(size 1.27 1.27)
				)
			)
		)
		(property "Value" ""
			(at 0 0 180)
			(layer "F.Fab")
			(effects
				(font
					(size 1.27 1.27)
				)
			)
		)
		(duplicate_pad_numbers_are_jumpers no)
		(fp_line
			(start 0.7874 0.4064)
			(end -0.7874 0.4064)
			(stroke
				(width 0.1524)
				(type default)
			)
			(layer "F.SilkS")
		)
		(fp_line
			(start 0.7874 -0.4064)
			(end 0.7874 0.4064)
			(stroke
				(width 0.1524)
				(type default)
			)
			(layer "F.SilkS")
		)
		(fp_line
			(start -0.7874 0.4064)
			(end -0.7874 -0.4064)
			(stroke
				(width 0.1524)
				(type default)
			)
			(layer "F.SilkS")
		)
		(fp_line
			(start -0.7874 -0.4064)
			(end 0.7874 -0.4064)
			(stroke
				(width 0.1524)
				(type default)
			)
			(layer "F.SilkS")
		)
		(fp_line
			(start 0.67945 0.3048)
			(end 0.120396 0.3048)
			(stroke
				(width 0.1)
				(type default)
			)
			(layer "F.Fab")
		)
		(fp_line
			(start 0.67945 -0.3048)
			(end 0.67945 0.3048)
			(stroke
				(width 0.1)
				(type default)
			)
			(layer "F.Fab")
		)
		(fp_line
			(start 0.12065 -0.2794)
			(end 0.12065 -0.3048)
			(stroke
				(width 0.1)
				(type default)
			)
			(layer "F.Fab")
		)
		(fp_line
			(start 0.12065 -0.3048)
			(end 0.67945 -0.3048)
			(stroke
				(width 0.1)
				(type default)
			)
			(layer "F.Fab")
		)
		(fp_line
			(start 0.120396 0.3048)
			(end 0.120396 0.2794)
			(stroke
				(width 0.1)
				(type default)
			)
			(layer "F.Fab")
		)
		(fp_line
			(start 0.120396 0.2794)
			(end -0.12065 0.2794)
			(stroke
				(width 0.1)
				(type default)
			)
			(layer "F.Fab")
		)
		(fp_line
			(start -0.12065 0.3048)
			(end -0.67945 0.3048)
			(stroke
				(width 0.1)
				(type default)
			)
			(layer "F.Fab")
		)
		(fp_line
			(start -0.12065 0.2794)
			(end -0.12065 0.3048)
			(stroke
				(width 0.1)
				(type default)
			)
			(layer "F.Fab")
		)
		(fp_line
			(start -0.12065 -0.2794)
			(end 0.12065 -0.2794)
			(stroke
				(width 0.1)
				(type default)
			)
			(layer "F.Fab")
		)
		(fp_line
			(start -0.12065 -0.305054)
			(end -0.12065 -0.2794)
			(stroke
				(width 0.1)
				(type default)
			)
			(layer "F.Fab")
		)
		(fp_line
			(start -0.67945 0.3048)
			(end -0.67945 -0.305054)
			(stroke
				(width 0.1)
				(type default)
			)
			(layer "F.Fab")
		)
		(fp_line
			(start -0.67945 -0.305054)
			(end -0.12065 -0.305054)
			(stroke
				(width 0.1)
				(type default)
			)
			(layer "F.Fab")
		)
		(pad "1" smd circle
			(at -0.40005 0 180)
			(size 0 0)
			(layers "F.Cu" "F.Mask" "F.Paste")
			(net "P3V3_AUX")
		)
		(pad "2" smd circle
			(at 0.40005 0 180)
			(size 0 0)
			(layers "F.Cu" "F.Mask" "F.Paste")
			(net "GND")
		)
	)
	(footprint ""
		(layer "F.Cu")
		(at 72.099678 -171.2341)
		(property "Reference" "PC309_5"
			(at 0 0 0)
			(layer "F.SilkS")
			(hide yes)
			(effects
				(font
					(size 1.27 1.27)
				)
			)
		)
		(property "Value" ""
			(at 0 0 0)
			(layer "F.Fab")
			(effects
				(font
					(size 1.27 1.27)
				)
			)
		)
		(duplicate_pad_numbers_are_jumpers no)
		(fp_line
			(start -0.7874 -0.4064)
			(end 0.7874 -0.4064)
			(stroke
				(width 0.1524)
				(type default)
			)
			(layer "F.SilkS")
		)
		(fp_line
			(start -0.7874 0.4064)
			(end -0.7874 -0.4064)
			(stroke
				(width 0.1524)
				(type default)
			)
			(layer "F.SilkS")
		)
		(fp_line
			(start 0.7874 -0.4064)
			(end 0.7874 0.4064)
			(stroke
				(width 0.1524)
				(type default)
			)
			(layer "F.SilkS")
		)
		(fp_line
			(start 0.7874 0.4064)
			(end -0.7874 0.4064)
			(stroke
				(width 0.1524)
				(type default)
			)
			(layer "F.SilkS")
		)
		(fp_line
			(start -0.67945 -0.305054)
			(end -0.12065 -0.305054)
			(stroke
				(width 0.1)
				(type default)
			)
			(layer "F.Fab")
		)
		(fp_line
			(start -0.67945 0.3048)
			(end -0.67945 -0.305054)
			(stroke
				(width 0.1)
				(type default)
			)
			(layer "F.Fab")
		)
		(fp_line
			(start -0.12065 -0.305054)
			(end -0.12065 -0.2794)
			(stroke
				(width 0.1)
				(type default)
			)
			(layer "F.Fab")
		)
		(fp_line
			(start -0.12065 -0.2794)
			(end 0.12065 -0.2794)
			(stroke
				(width 0.1)
				(type default)
			)
			(layer "F.Fab")
		)
		(fp_line
			(start -0.12065 0.2794)
			(end -0.12065 0.3048)
			(stroke
				(width 0.1)
				(type default)
			)
			(layer "F.Fab")
		)
		(fp_line
			(start -0.12065 0.3048)
			(end -0.67945 0.3048)
			(stroke
				(width 0.1)
				(type default)
			)
			(layer "F.Fab")
		)
		(fp_line
			(start 0.120396 0.2794)
			(end -0.12065 0.2794)
			(stroke
				(width 0.1)
				(type default)
			)
			(layer "F.Fab")
		)
		(fp_line
			(start 0.120396 0.3048)
			(end 0.120396 0.2794)
			(stroke
				(width 0.1)
				(type default)
			)
			(layer "F.Fab")
		)
		(fp_line
			(start 0.12065 -0.3048)
			(end 0.67945 -0.3048)
			(stroke
				(width 0.1)
				(type default)
			)
			(layer "F.Fab")
		)
		(fp_line
			(start 0.12065 -0.2794)
			(end 0.12065 -0.3048)
			(stroke
				(width 0.1)
				(type default)
			)
			(layer "F.Fab")
		)
		(fp_line
			(start 0.67945 -0.3048)
			(end 0.67945 0.3048)
			(stroke
				(width 0.1)
				(type default)
			)
			(layer "F.Fab")
		)
		(fp_line
			(start 0.67945 0.3048)
			(end 0.120396 0.3048)
			(stroke
				(width 0.1)
				(type default)
			)
			(layer "F.Fab")
		)
		(pad "1" smd circle
			(at -0.40005 0)
			(size 0 0)
			(layers "F.Cu" "F.Mask" "F.Paste")
			(net "SW_P12V_AUX_PVDDCR_CPU0_P1_FLT")
		)
		(pad "2" smd circle
			(at 0.40005 0)
			(size 0 0)
			(layers "F.Cu" "F.Mask" "F.Paste")
			(net "GND")
		)
	)
	(footprint ""
		(layer "F.Cu")
		(at 317.041276 -340.206838)
		(property "Reference" "PR86"
			(at 0 0 0)
			(layer "F.SilkS")
			(hide yes)
			(effects
				(font
					(size 1.27 1.27)
				)
			)
		)
		(property "Value" ""
			(at 0 0 0)
			(layer "F.Fab")
			(effects
				(font
					(size 1.27 1.27)
				)
			)
		)
		(duplicate_pad_numbers_are_jumpers no)
		(fp_line
			(start -0.7874 -0.4064)
			(end 0.7874 -0.4064)
			(stroke
				(width 0.1524)
				(type default)
			)
			(layer "F.SilkS")
		)
		(fp_line
			(start -0.7874 0.4064)
			(end -0.7874 -0.4064)
			(stroke
				(width 0.1524)
				(type default)
			)
			(layer "F.SilkS")
		)
		(fp_line
			(start 0.7874 -0.4064)
			(end 0.7874 0.4064)
			(stroke
				(width 0.1524)
				(type default)
			)
			(layer "F.SilkS")
		)
		(fp_line
			(start 0.7874 0.4064)
			(end -0.7874 0.4064)
			(stroke
				(width 0.1524)
				(type default)
			)
			(layer "F.SilkS")
		)
		(fp_line
			(start -0.67945 -0.305054)
			(end -0.12065 -0.305054)
			(stroke
				(width 0.1)
				(type default)
			)
			(layer "F.Fab")
		)
		(fp_line
			(start -0.67945 0.3048)
			(end -0.67945 -0.305054)
			(stroke
				(width 0.1)
				(type default)
			)
			(layer "F.Fab")
		)
		(fp_line
			(start -0.12065 -0.305054)
			(end -0.12065 -0.2794)
			(stroke
				(width 0.1)
				(type default)
			)
			(layer "F.Fab")
		)
		(fp_line
			(start -0.12065 -0.2794)
			(end 0.12065 -0.2794)
			(stroke
				(width 0.1)
				(type default)
			)
			(layer "F.Fab")
		)
		(fp_line
			(start -0.12065 0.2794)
			(end -0.12065 0.3048)
			(stroke
				(width 0.1)
				(type default)
			)
			(layer "F.Fab")
		)
		(fp_line
			(start -0.12065 0.3048)
			(end -0.67945 0.3048)
			(stroke
				(width 0.1)
				(type default)
			)
			(layer "F.Fab")
		)
		(fp_line
			(start 0.120396 0.2794)
			(end -0.12065 0.2794)
			(stroke
				(width 0.1)
				(type default)
			)
			(layer "F.Fab")
		)
		(fp_line
			(start 0.120396 0.3048)
			(end 0.120396 0.2794)
			(stroke
				(width 0.1)
				(type default)
			)
			(layer "F.Fab")
		)
		(fp_line
			(start 0.12065 -0.3048)
			(end 0.67945 -0.3048)
			(stroke
				(width 0.1)
				(type default)
			)
			(layer "F.Fab")
		)
		(fp_line
			(start 0.12065 -0.2794)
			(end 0.12065 -0.3048)
			(stroke
				(width 0.1)
				(type default)
			)
			(layer "F.Fab")
		)
		(fp_line
			(start 0.67945 -0.3048)
			(end 0.67945 0.3048)
			(stroke
				(width 0.1)
				(type default)
			)
			(layer "F.Fab")
		)
		(fp_line
			(start 0.67945 0.3048)
			(end 0.120396 0.3048)
			(stroke
				(width 0.1)
				(type default)
			)
			(layer "F.Fab")
		)
		(pad "1" smd circle
			(at -0.40005 0)
			(size 0 0)
			(layers "F.Cu" "F.Mask" "F.Paste")
			(net "PVDDCR_CPU1_P0_LSET3")
		)
		(pad "2" smd circle
			(at 0.40005 0)
			(size 0 0)
			(layers "F.Cu" "F.Mask" "F.Paste")
			(net "GND")
		)
	)
)
